# S9S_MB_2U (Grand Teton) — schematic netlist excerpt (pin names and nets, part order shuffled) for the footprints in the layout excerpt that follows; sources: Cadence DE-HDL packaged netlist, KiCad conversion of 03242023_DA0F0TMBIJ0_F0T_Motherboard_J_brd_V01_OCP.brd

PC604_P0_1  Q_CAP  1UF 16V 10% X6S  pkg C0402  page 271 : A = SW_P12V_PVCCFA_EHV_FIVRA_CPU0_R ; B = GND
R3067  Q_RES  0 5% CHIP  pkg 0402LF  page 214 : A = FM_SMB_2_ALERT_GPU_ISO_N ; B = FM_SMB_2_ALERT_GPU_ISO_R_N

(kicad_pcb
	(version 20260206)
	(generator "pcbnew")
	(generator_version "10.0")
	(general
		(thickness 1.6)
		(legacy_teardrops no)
	)
	(paper "A4")
	(title_block
		(title "03242023_DA0F0TMBIJ0_F0T_Motherboard_J_brd_V01_OCP.brd")
		(comment 1 "Grand Teton / footprints 1999-2000 of 6105")
	)
	(layers
		(0 "F.Cu" signal "TOP")
		(4 "In1.Cu" signal "GND")
		(6 "In2.Cu" signal "IN1")
		(8 "In3.Cu" signal "GND1")
		(10 "In4.Cu" signal "IN2")
		(12 "In5.Cu" signal "GND2")
		(14 "In6.Cu" signal "IN3")
		(16 "In7.Cu" signal "GND3")
		(18 "In8.Cu" signal "VCC")
		(20 "In9.Cu" signal "VCC1")
		(22 "In10.Cu" signal "GND4")
		(24 "In11.Cu" signal "IN4")
		(26 "In12.Cu" signal "GND5")
		(28 "In13.Cu" signal "IN5")
		(30 "In14.Cu" signal "GND6")
		(32 "In15.Cu" signal "IN6")
		(34 "In16.Cu" signal "GND7")
		(2 "B.Cu" signal "BOTTOM")
		(9 "F.Adhes" user "F.Adhesive")
		(11 "B.Adhes" user "B.Adhesive")
		(13 "F.Paste" user "Package Geometry/Pastemask Top")
		(15 "B.Paste" user "Package Geometry/Pastemask Bottom")
		(5 "F.SilkS" user "Ref Des/Silkscreen Top")
		(7 "B.SilkS" user "Ref Des/Silkscreen Bottom")
		(1 "F.Mask" user "Board Geometry/Soldermask Top")
		(3 "B.Mask" user "Board Geometry/Soldermask Bottom")
		(17 "Dwgs.User" user "User.Drawings")
		(19 "Cmts.User" user "User.Comments")
		(21 "Eco1.User" user "User.Eco1")
		(23 "Eco2.User" user "User.Eco2")
		(25 "Edge.Cuts" user "Board Geometry/Outline")
		(27 "Margin" user)
		(31 "F.CrtYd" user "Package Geometry/Place Bound Top")
		(29 "B.CrtYd" user "Package Geometry/Place Bound Bottom")
		(35 "F.Fab" user "Ref Des/Assembly Top")
		(33 "B.Fab" user "Ref Des/Assembly Bottom")
	)
	(footprint ""
		(layer "F.Cu")
		(at 419.731698 -362.155994 -90)
		(property "Reference" "PC604_P0_1"
			(at 0 0 270)
			(layer "F.SilkS")
			(hide yes)
			(effects
				(font
					(size 1.27 1.27)
				)
			)
		)
		(property "Value" ""
			(at 0 0 270)
			(layer "F.Fab")
			(effects
				(font
					(size 1.27 1.27)
				)
			)
		)
		(duplicate_pad_numbers_are_jumpers no)
		(fp_line
			(start -0.7874 0.4064)
			(end -0.7874 -0.4064)
			(stroke
				(width 0.1524)
				(type default)
			)
			(layer "F.SilkS")
		)
		(fp_line
			(start 0.7874 0.4064)
			(end -0.7874 0.4064)
			(stroke
				(width 0.1524)
				(type default)
			)
			(layer "F.SilkS")
		)
		(fp_line
			(start -0.7874 -0.4064)
			(end 0.7874 -0.4064)
			(stroke
				(width 0.1524)
				(type default)
			)
			(layer "F.SilkS")
		)
		(fp_line
			(start 0.7874 -0.4064)
			(end 0.7874 0.4064)
			(stroke
				(width 0.1524)
				(type default)
			)
			(layer "F.SilkS")
		)
		(fp_line
			(start -0.67945 0.3048)
			(end -0.67945 -0.305054)
			(stroke
				(width 0.1)
				(type default)
			)
			(layer "F.Fab")
		)
		(fp_line
			(start -0.12065 0.3048)
			(end -0.67945 0.3048)
			(stroke
				(width 0.1)
				(type default)
			)
			(layer "F.Fab")
		)
		(fp_line
			(start 0.120396 0.3048)
			(end 0.120396 0.2794)
			(stroke
				(width 0.1)
				(type default)
			)
			(layer "F.Fab")
		)
		(fp_line
			(start 0.67945 0.3048)
			(end 0.120396 0.3048)
			(stroke
				(width 0.1)
				(type default)
			)
			(layer "F.Fab")
		)
		(fp_line
			(start -0.12065 0.2794)
			(end -0.12065 0.3048)
			(stroke
				(width 0.1)
				(type default)
			)
			(layer "F.Fab")
		)
		(fp_line
			(start 0.120396 0.2794)
			(end -0.12065 0.2794)
			(stroke
				(width 0.1)
				(type default)
			)
			(layer "F.Fab")
		)
		(fp_line
			(start -0.12065 -0.2794)
			(end 0.12065 -0.2794)
			(stroke
				(width 0.1)
				(type default)
			)
			(layer "F.Fab")
		)
		(fp_line
			(start 0.12065 -0.2794)
			(end 0.12065 -0.3048)
			(stroke
				(width 0.1)
				(type default)
			)
			(layer "F.Fab")
		)
		(fp_line
			(start 0.12065 -0.3048)
			(end 0.67945 -0.3048)
			(stroke
				(width 0.1)
				(type default)
			)
			(layer "F.Fab")
		)
		(fp_line
			(start 0.67945 -0.3048)
			(end 0.67945 0.3048)
			(stroke
				(width 0.1)
				(type default)
			)
			(layer "F.Fab")
		)
		(fp_line
			(start -0.67945 -0.305054)
			(end -0.12065 -0.305054)
			(stroke
				(width 0.1)
				(type default)
			)
			(layer "F.Fab")
		)
		(fp_line
			(start -0.12065 -0.305054)
			(end -0.12065 -0.2794)
			(stroke
				(width 0.1)
				(type default)
			)
			(layer "F.Fab")
		)
		(pad "1" smd circle
			(at -0.40005 0 270)
			(size 0 0)
			(layers "F.Cu" "F.Mask" "F.Paste")
			(net "SW_P12V_PVCCFA_EHV_FIVRA_CPU0_R")
		)
		(pad "2" smd circle
			(at 0.40005 0 270)
			(size 0 0)
			(layers "F.Cu" "F.Mask" "F.Paste")
			(net "GND")
		)
	)
	(footprint ""
		(layer "F.Cu")
		(at 21.801582 -423.629836 -90)
		(property "Reference" "R3067"
			(at 0 0 270)
			(layer "F.SilkS")
			(hide yes)
			(effects
				(font
					(size 1.27 1.27)
				)
			)
		)
		(property "Value" ""
			(at 0 0 270)
			(layer "F.Fab")
			(effects
				(font
					(size 1.27 1.27)
				)
			)
		)
		(duplicate_pad_numbers_are_jumpers no)
		(fp_line
			(start -0.7874 0.4064)
			(end -0.7874 -0.4064)
			(stroke
				(width 0.1524)
				(type default)
			)
			(layer "F.SilkS")
		)
		(fp_line
			(start 0.7874 0.4064)
			(end -0.7874 0.4064)
			(stroke
				(width 0.1524)
				(type default)
			)
			(layer "F.SilkS")
		)
		(fp_line
			(start -0.7874 -0.4064)
			(end 0.7874 -0.4064)
			(stroke
				(width 0.1524)
				(type default)
			)
			(layer "F.SilkS")
		)
		(fp_line
			(start 0.7874 -0.4064)
			(end 0.7874 0.4064)
			(stroke
				(width 0.1524)
				(type default)
			)
			(layer "F.SilkS")
		)
		(fp_line
			(start -0.67945 0.3048)
			(end -0.67945 -0.305054)
			(stroke
				(width 0.1)
				(type default)
			)
			(layer "F.Fab")
		)
		(fp_line
			(start -0.12065 0.3048)
			(end -0.67945 0.3048)
			(stroke
				(width 0.1)
				(type default)
			)
			(layer "F.Fab")
		)
		(fp_line
			(start 0.120396 0.3048)
			(end 0.120396 0.2794)
			(stroke
				(width 0.1)
				(type default)
			)
			(layer "F.Fab")
		)
		(fp_line
			(start 0.67945 0.3048)
			(end 0.120396 0.3048)
			(stroke
				(width 0.1)
				(type default)
			)
			(layer "F.Fab")
		)
		(fp_line
			(start -0.12065 0.2794)
			(end -0.12065 0.3048)
			(stroke
				(width 0.1)
				(type default)
			)
			(layer "F.Fab")
		)
		(fp_line
			(start 0.120396 0.2794)
			(end -0.12065 0.2794)
			(stroke
				(width 0.1)
				(type default)
			)
			(layer "F.Fab")
		)
		(fp_line
			(start -0.12065 -0.2794)
			(end 0.12065 -0.2794)
			(stroke
				(width 0.1)
				(type default)
			)
			(layer "F.Fab")
		)
		(fp_line
			(start 0.12065 -0.2794)
			(end 0.12065 -0.3048)
			(stroke
				(width 0.1)
				(type default)
			)
			(layer "F.Fab")
		)
		(fp_line
			(start 0.12065 -0.3048)
			(end 0.67945 -0.3048)
			(stroke
				(width 0.1)
				(type default)
			)
			(layer "F.Fab")
		)
		(fp_line
			(start 0.67945 -0.3048)
			(end 0.67945 0.3048)
			(stroke
				(width 0.1)
				(type default)
			)
			(layer "F.Fab")
		)
		(fp_line
			(start -0.67945 -0.305054)
			(end -0.12065 -0.305054)
			(stroke
				(width 0.1)
				(type default)
			)
			(layer "F.Fab")
		)
		(fp_line
			(start -0.12065 -0.305054)
			(end -0.12065 -0.2794)
			(stroke
				(width 0.1)
				(type default)
			)
			(layer "F.Fab")
		)
		(pad "1" smd circle
			(at -0.40005 0 270)
			(size 0 0)
			(layers "F.Cu" "F.Mask" "F.Paste")
			(net "FM_SMB_2_ALERT_GPU_ISO_N")
		)
		(pad "2" smd circle
			(at 0.40005 0 270)
			(size 0 0)
			(layers "F.Cu" "F.Mask" "F.Paste")
			(net "FM_SMB_2_ALERT_GPU_ISO_R_N")
		)
	)
)
